(kicad_pcb
	(version 20260206)
	(generator "pcbnew")
	(generator_version "10.0")
	(general
		(thickness 1.6)
		(legacy_teardrops no)
	)
	(paper "A4")
	(title_block
		(title "Bryce Canyon_R.DPB_16317-1_OCP.brd")
		(comment 1 "Bryce Canyon / footprints 1203-1210 of 2099")
	)
	(layers
		(0 "F.Cu" signal "TOP")
		(4 "In1.Cu" signal "L2GND")
		(6 "In2.Cu" signal "L3")
		(8 "In3.Cu" signal "L4VCC")
		(10 "In4.Cu" signal "L5VCC")
		(12 "In5.Cu" signal "L6")
		(14 "In6.Cu" signal "L7GND")
		(2 "B.Cu" signal "BOTTOM")
		(9 "F.Adhes" user "F.Adhesive")
		(11 "B.Adhes" user "B.Adhesive")
		(13 "F.Paste" user "Package Geometry/Pastemask Top")
		(15 "B.Paste" user "Package Geometry/Pastemask Bottom")
		(5 "F.SilkS" user "Ref Des/Silkscreen Top")
		(7 "B.SilkS" user "Ref Des/Silkscreen Bottom")
		(1 "F.Mask" user "Board Geometry/Soldermask Top")
		(3 "B.Mask" user "Board Geometry/Soldermask Bottom")
		(17 "Dwgs.User" user "User.Drawings")
		(19 "Cmts.User" user "User.Comments")
		(21 "Eco1.User" user "User.Eco1")
		(23 "Eco2.User" user "User.Eco2")
		(25 "Edge.Cuts" user "Board Geometry/Outline")
		(27 "Margin" user)
		(31 "F.CrtYd" user "Package Geometry/Place Bound Top")
		(29 "B.CrtYd" user "Package Geometry/Place Bound Bottom")
		(35 "F.Fab" user "Ref Des/Assembly Top")
		(33 "B.Fab" user "Ref Des/Assembly Bottom")
	)
	(footprint ""
		(layer "F.Cu")
		(at 181.356 -14.5796 90)
		(property "Reference" "R754"
			(at 0 0 90)
			(layer "F.SilkS")
			(hide yes)
			(effects
				(font
					(size 1.27 1.27)
				)
			)
		)
		(property "Value" "0R2J-2-GP"
			(at 0.064008 -3.993896 90)
			(unlocked yes)
			(layer "F.Fab")
			(hide yes)
			(effects
				(font
					(size 1.016 1.016)
					(thickness 0.1524)
				)
			)
		)
		(property "Device Type" "R402H16"
			(at 0.064008 -5.517896 90)
			(unlocked yes)
			(layer "F.Fab")
			(hide yes)
			(effects
				(font
					(size 1.016 1.016)
					(thickness 0.1524)
				)
			)
		)
		(duplicate_pad_numbers_are_jumpers no)
		(fp_line
			(start 0.508 -0.9398)
			(end -0.508 -0.9398)
			(stroke
				(width 0.1524)
				(type default)
			)
			(layer "F.SilkS")
		)
		(fp_line
			(start -0.508 -0.9398)
			(end -0.508 0.9398)
			(stroke
				(width 0.1524)
				(type default)
			)
			(layer "F.SilkS")
		)
		(fp_rect
			(start -0.508 0.9398)
			(end 0.508 -0.9398)
			(stroke
				(width 0)
				(type default)
			)
			(fill no)
			(layer "F.CrtYd")
		)
		(fp_rect
			(start -0.508 0.9398)
			(end 0.508 -0.9398)
			(stroke
				(width 0)
				(type default)
			)
			(fill no)
			(layer "F.Fab")
		)
		(pad "1" smd custom
			(at 0 -0.4445 90)
			(size 0.1397 0.1397)
			(layers "F.Cu" "F.Mask" "F.Paste")
			(net "SW_HDD_G29")
			(options
				(clearance outline)
				(anchor circle)
			)
			(primitives
				(gr_poly
					(pts
						(arc
							(start -0.1778 -0.2794)
							(mid -0.249642 -0.249642)
							(end -0.2794 -0.1778)
						)
						(arc
							(start -0.2794 0.1778)
							(mid -0.249642 0.249642)
							(end -0.1778 0.2794)
						)
						(arc
							(start 0.1778 0.2794)
							(mid 0.249642 0.249642)
							(end 0.2794 0.1778)
						)
						(arc
							(start 0.2794 -0.1778)
							(mid 0.249642 -0.249642)
							(end 0.1778 -0.2794)
						)
					)
					(width 0)
					(fill yes)
				)
			)
		)
		(pad "2" smd custom
			(at 0 0.4445 90)
			(size 0.1397 0.1397)
			(layers "F.Cu" "F.Mask" "F.Paste")
			(net "SW_HDD_R29")
			(options
				(clearance outline)
				(anchor circle)
			)
			(primitives
				(gr_poly
					(pts
						(arc
							(start -0.1778 -0.2794)
							(mid -0.249642 -0.249642)
							(end -0.2794 -0.1778)
						)
						(arc
							(start -0.2794 0.1778)
							(mid -0.249642 0.249642)
							(end -0.1778 0.2794)
						)
						(arc
							(start 0.1778 0.2794)
							(mid 0.249642 0.249642)
							(end 0.2794 0.1778)
						)
						(arc
							(start 0.2794 -0.1778)
							(mid 0.249642 -0.249642)
							(end 0.1778 -0.2794)
						)
					)
					(width 0)
					(fill yes)
				)
			)
		)
	)
	(footprint ""
		(layer "F.Cu")
		(at 82.042 -265.684 90)
		(property "Reference" "R192"
			(at 0 0 90)
			(layer "F.SilkS")
			(hide yes)
			(effects
				(font
					(size 1.27 1.27)
				)
			)
		)
		(property "Value" "2R6F-GP"
			(at -0.0508 -4.8514 90)
			(unlocked yes)
			(layer "F.Fab")
			(hide yes)
			(effects
				(font
					(size 1.016 1.016)
					(thickness 0.1524)
				)
			)
		)
		(property "Device Type" "R1206H26"
			(at 0 -6.3754 90)
			(unlocked yes)
			(layer "F.Fab")
			(hide yes)
			(effects
				(font
					(size 1.016 1.016)
					(thickness 0.1524)
				)
			)
		)
		(duplicate_pad_numbers_are_jumpers no)
		(fp_line
			(start 1.016 -2.2352)
			(end 1.016 2.2352)
			(stroke
				(width 0.1524)
				(type default)
			)
			(layer "F.SilkS")
		)
		(fp_line
			(start -1.016 -2.2352)
			(end 1.016 -2.2352)
			(stroke
				(width 0.1524)
				(type default)
			)
			(layer "F.SilkS")
		)
		(fp_line
			(start 1.016 2.2352)
			(end -1.016 2.2352)
			(stroke
				(width 0.1524)
				(type default)
			)
			(layer "F.SilkS")
		)
		(fp_line
			(start -1.016 2.2352)
			(end -1.016 -2.2352)
			(stroke
				(width 0.1524)
				(type default)
			)
			(layer "F.SilkS")
		)
		(fp_rect
			(start -1.0922 2.3114)
			(end 1.0922 -2.3114)
			(stroke
				(width 0)
				(type default)
			)
			(fill no)
			(layer "F.CrtYd")
		)
		(fp_poly
			(pts
				(xy -1.0922 -2.3114) (xy 1.0922 -2.3114) (xy 1.0922 2.3114) (xy -1.0922 2.3114)
			)
			(stroke
				(width 0)
				(type default)
			)
			(fill no)
			(layer "F.Fab")
		)
		(pad "1" smd rect
			(at 0 -1.397 90)
			(size 1.651 1.27)
			(layers "F.Cu" "F.Mask" "F.Paste")
			(net "P12V_HDD2")
		)
		(pad "2" smd rect
			(at 0 1.397 90)
			(size 1.651 1.27)
			(layers "F.Cu" "F.Mask" "F.Paste")
			(net "12V_PRE_2")
		)
	)
	(footprint ""
		(layer "F.Cu")
		(at 331.7494 -250.4948 -90)
		(property "Reference" "C116"
			(at 0 0 270)
			(layer "F.SilkS")
			(hide yes)
			(effects
				(font
					(size 1.27 1.27)
				)
			)
		)
		(property "Value" "SCD033U25V2KX-GP"
			(at 1.1811 -2.7051 270)
			(unlocked yes)
			(layer "F.Fab")
			(hide yes)
			(effects
				(font
					(size 1.016 1.016)
					(thickness 0.1524)
				)
			)
		)
		(property "Device Type" "C402H22"
			(at 1.1811 -4.2291 270)
			(unlocked yes)
			(layer "F.Fab")
			(hide yes)
			(effects
				(font
					(size 1.016 1.016)
					(thickness 0.1524)
				)
			)
		)
		(duplicate_pad_numbers_are_jumpers no)
		(fp_rect
			(start -0.4318 0.9525)
			(end 0.4318 -0.9525)
			(stroke
				(width 0)
				(type default)
			)
			(fill no)
			(layer "F.CrtYd")
		)
		(fp_rect
			(start -0.4318 0.9525)
			(end 0.4318 -0.9525)
			(stroke
				(width 0)
				(type default)
			)
			(fill no)
			(layer "F.Fab")
		)
		(pad "1" smd custom
			(at 0 -0.4445 270)
			(size 0.1524 0.1524)
			(layers "F.Cu" "F.Mask" "F.Paste")
			(net "SW_HDD_P6")
			(options
				(clearance outline)
				(anchor circle)
			)
			(primitives
				(gr_poly
					(pts
						(arc
							(start 0.3048 -0.2032)
							(mid 0.275042 -0.275042)
							(end 0.2032 -0.3048)
						)
						(arc
							(start -0.2032 -0.3048)
							(mid -0.275042 -0.275042)
							(end -0.3048 -0.2032)
						)
						(arc
							(start -0.3048 0.2032)
							(mid -0.275042 0.275042)
							(end -0.2032 0.3048)
						)
						(arc
							(start 0.2032 0.3048)
							(mid 0.275042 0.275042)
							(end 0.3048 0.2032)
						)
					)
					(width 0)
					(fill yes)
				)
			)
		)
		(pad "2" smd custom
			(at 0 0.4445 270)
			(size 0.1524 0.1524)
			(layers "F.Cu" "F.Mask" "F.Paste")
			(net "GND")
			(options
				(clearance outline)
				(anchor circle)
			)
			(primitives
				(gr_poly
					(pts
						(arc
							(start 0.3048 -0.2032)
							(mid 0.275042 -0.275042)
							(end 0.2032 -0.3048)
						)
						(arc
							(start -0.2032 -0.3048)
							(mid -0.275042 -0.275042)
							(end -0.3048 -0.2032)
						)
						(arc
							(start -0.3048 0.2032)
							(mid -0.275042 0.275042)
							(end -0.2032 0.3048)
						)
						(arc
							(start 0.2032 0.3048)
							(mid 0.275042 0.275042)
							(end 0.3048 0.2032)
						)
					)
					(width 0)
					(fill yes)
				)
			)
		)
	)
	(footprint ""
		(layer "F.Cu")
		(at 454.98766 -222.048324 90)
		(property "Reference" "C658"
			(at 0 0 90)
			(layer "F.SilkS")
			(hide yes)
			(effects
				(font
					(size 1.27 1.27)
				)
			)
		)
		(property "Value" "SC10U16V5KX-7-GP-U"
			(at -0.0762 -6.1214 90)
			(unlocked yes)
			(layer "F.Fab")
			(hide yes)
			(effects
				(font
					(size 1.016 1.016)
					(thickness 0.1524)
				)
			)
		)
		(property "Device Type" "C805H58"
			(at -0.0762 -8.1534 90)
			(unlocked yes)
			(layer "F.Fab")
			(hide yes)
			(effects
				(font
					(size 1.016 1.016)
					(thickness 0.1524)
				)
			)
		)
		(duplicate_pad_numbers_are_jumpers no)
		(fp_line
			(start 0.635 0)
			(end -0.635 0)
			(stroke
				(width 0.508)
				(type default)
			)
			(layer "F.SilkS")
		)
		(fp_rect
			(start -0.9652 1.778)
			(end 0.9652 -1.778)
			(stroke
				(width 0)
				(type default)
			)
			(fill no)
			(layer "F.CrtYd")
		)
		(fp_poly
			(pts
				(xy -0.9652 -1.778) (xy 0.9652 -1.778) (xy 0.9652 1.778) (xy -0.9652 1.778)
			)
			(stroke
				(width 0)
				(type default)
			)
			(fill no)
			(layer "F.Fab")
		)
		(pad "1" smd rect
			(at 0 -0.9652 90)
			(size 1.397 1.143)
			(layers "F.Cu" "F.Mask" "F.Paste")
			(net "P12V_B_3_VIN_U33")
		)
		(pad "2" smd rect
			(at 0 0.9652 90)
			(size 1.397 1.143)
			(layers "F.Cu" "F.Mask" "F.Paste")
			(net "GND")
		)
	)
	(footprint ""
		(layer "F.Cu")
		(at 176.276 -374.904 90)
		(property "Reference" "C542"
			(at 0 0 90)
			(layer "F.SilkS")
			(hide yes)
			(effects
				(font
					(size 1.27 1.27)
				)
			)
		)
		(property "Value" "SCD1U16V2KX-3GP"
			(at 1.1811 -2.7051 90)
			(unlocked yes)
			(layer "F.Fab")
			(hide yes)
			(effects
				(font
					(size 1.016 1.016)
					(thickness 0.1524)
				)
			)
		)
		(property "Device Type" "C402H22"
			(at 1.1811 -4.2291 90)
			(unlocked yes)
			(layer "F.Fab")
			(hide yes)
			(effects
				(font
					(size 1.016 1.016)
					(thickness 0.1524)
				)
			)
		)
		(duplicate_pad_numbers_are_jumpers no)
		(fp_rect
			(start -0.4318 0.9525)
			(end 0.4318 -0.9525)
			(stroke
				(width 0)
				(type default)
			)
			(fill no)
			(layer "F.CrtYd")
		)
		(fp_rect
			(start -0.4318 0.9525)
			(end 0.4318 -0.9525)
			(stroke
				(width 0)
				(type default)
			)
			(fill no)
			(layer "F.Fab")
		)
		(pad "1" smd custom
			(at 0 -0.4445 90)
			(size 0.1524 0.1524)
			(layers "F.Cu" "F.Mask" "F.Paste")
			(net "MB0_CM_VOUT_R")
			(options
				(clearance outline)
				(anchor circle)
			)
			(primitives
				(gr_poly
					(pts
						(arc
							(start 0.3048 -0.2032)
							(mid 0.275042 -0.275042)
							(end 0.2032 -0.3048)
						)
						(arc
							(start -0.2032 -0.3048)
							(mid -0.275042 -0.275042)
							(end -0.3048 -0.2032)
						)
						(arc
							(start -0.3048 0.2032)
							(mid -0.275042 0.275042)
							(end -0.2032 0.3048)
						)
						(arc
							(start 0.2032 0.3048)
							(mid 0.275042 0.275042)
							(end 0.3048 0.2032)
						)
					)
					(width 0)
					(fill yes)
				)
			)
		)
		(pad "2" smd custom
			(at 0 0.4445 90)
			(size 0.1524 0.1524)
			(layers "F.Cu" "F.Mask" "F.Paste")
			(net "AGND_CURRENT_MON")
			(options
				(clearance outline)
				(anchor circle)
			)
			(primitives
				(gr_poly
					(pts
						(arc
							(start 0.3048 -0.2032)
							(mid 0.275042 -0.275042)
							(end 0.2032 -0.3048)
						)
						(arc
							(start -0.2032 -0.3048)
							(mid -0.275042 -0.275042)
							(end -0.3048 -0.2032)
						)
						(arc
							(start -0.3048 0.2032)
							(mid -0.275042 0.275042)
							(end -0.2032 0.3048)
						)
						(arc
							(start 0.2032 0.3048)
							(mid 0.275042 0.275042)
							(end 0.3048 0.2032)
						)
					)
					(width 0)
					(fill yes)
				)
			)
		)
	)
	(footprint ""
		(layer "F.Cu")
		(at 244.37848 -193.29654 -90)
		(property "Reference" "R74"
			(at 0 0 270)
			(layer "F.SilkS")
			(hide yes)
			(effects
				(font
					(size 1.27 1.27)
				)
			)
		)
		(property "Value" "4K7R2F-GP"
			(at 0.064008 -3.993896 270)
			(unlocked yes)
			(layer "F.Fab")
			(hide yes)
			(effects
				(font
					(size 1.016 1.016)
					(thickness 0.1524)
				)
			)
		)
		(property "Device Type" "R402H16"
			(at 0.064008 -5.517896 270)
			(unlocked yes)
			(layer "F.Fab")
			(hide yes)
			(effects
				(font
					(size 1.016 1.016)
					(thickness 0.1524)
				)
			)
		)
		(duplicate_pad_numbers_are_jumpers no)
		(fp_line
			(start -0.508 -0.9398)
			(end -0.508 0.9398)
			(stroke
				(width 0.1524)
				(type default)
			)
			(layer "F.SilkS")
		)
		(fp_line
			(start 0.508 -0.9398)
			(end -0.508 -0.9398)
			(stroke
				(width 0.1524)
				(type default)
			)
			(layer "F.SilkS")
		)
		(fp_rect
			(start -0.508 0.9398)
			(end 0.508 -0.9398)
			(stroke
				(width 0)
				(type default)
			)
			(fill no)
			(layer "F.CrtYd")
		)
		(fp_rect
			(start -0.508 0.9398)
			(end 0.508 -0.9398)
			(stroke
				(width 0)
				(type default)
			)
			(fill no)
			(layer "F.Fab")
		)
		(pad "1" smd custom
			(at 0 -0.4445 270)
			(size 0.1397 0.1397)
			(layers "F.Cu" "F.Mask" "F.Paste")
			(net "P3V3_STBY_B")
			(options
				(clearance outline)
				(anchor circle)
			)
			(primitives
				(gr_poly
					(pts
						(arc
							(start -0.1778 -0.2794)
							(mid -0.249642 -0.249642)
							(end -0.2794 -0.1778)
						)
						(arc
							(start -0.2794 0.1778)
							(mid -0.249642 0.249642)
							(end -0.1778 0.2794)
						)
						(arc
							(start 0.1778 0.2794)
							(mid 0.249642 0.249642)
							(end 0.2794 0.1778)
						)
						(arc
							(start 0.2794 -0.1778)
							(mid 0.249642 -0.249642)
							(end 0.1778 -0.2794)
						)
					)
					(width 0)
					(fill yes)
				)
			)
		)
		(pad "2" smd custom
			(at 0 0.4445 270)
			(size 0.1397 0.1397)
			(layers "F.Cu" "F.Mask" "F.Paste")
			(net "IO_EXP2_INT_N")
			(options
				(clearance outline)
				(anchor circle)
			)
			(primitives
				(gr_poly
					(pts
						(arc
							(start -0.1778 -0.2794)
							(mid -0.249642 -0.249642)
							(end -0.2794 -0.1778)
						)
						(arc
							(start -0.2794 0.1778)
							(mid -0.249642 0.249642)
							(end -0.1778 0.2794)
						)
						(arc
							(start 0.1778 0.2794)
							(mid 0.249642 0.249642)
							(end 0.2794 0.1778)
						)
						(arc
							(start 0.2794 -0.1778)
							(mid 0.249642 -0.249642)
							(end 0.1778 -0.2794)
						)
					)
					(width 0)
					(fill yes)
				)
			)
		)
	)
	(footprint ""
		(layer "F.Cu")
		(at 109.982 -14.3764)
		(property "Reference" "Q138"
			(at 0 0 0)
			(layer "F.SilkS")
			(hide yes)
			(effects
				(font
					(size 1.27 1.27)
				)
			)
		)
		(property "Value" "AO4407AL-GP"
			(at -3.707384 -1.5367 0)
			(unlocked yes)
			(layer "F.Fab")
			(hide yes)
			(effects
				(font
					(size 1.016 1.016)
					(thickness 0.1524)
				)
			)
		)
		(property "Device Type" "SOIC8H69"
			(at -3.707384 -3.0607 0)
			(unlocked yes)
			(layer "F.Fab")
			(hide yes)
			(effects
				(font
					(size 1.016 1.016)
					(thickness 0.1524)
				)
			)
		)
		(duplicate_pad_numbers_are_jumpers no)
		(fp_line
			(start -2.7432 -1.4224)
			(end -2.7432 1.4224)
			(stroke
				(width 0.1524)
				(type default)
			)
			(layer "F.SilkS")
		)
		(fp_line
			(start -2.7432 1.4224)
			(end -2.6416 1.4224)
			(stroke
				(width 0.1524)
				(type default)
			)
			(layer "F.SilkS")
		)
		(fp_line
			(start -2.7432 1.4224)
			(end 2.1336 1.4224)
			(stroke
				(width 0.1524)
				(type default)
			)
			(layer "F.SilkS")
		)
		(fp_line
			(start -2.7178 -0.508)
			(end -2.1844 -0.0508)
			(stroke
				(width 0.1524)
				(type default)
			)
			(layer "F.SilkS")
		)
		(fp_line
			(start -2.6289 3.4417)
			(end -2.6289 1.4732)
			(stroke
				(width 0.381)
				(type default)
			)
			(layer "F.SilkS")
		)
		(fp_line
			(start -2.1844 -0.0508)
			(end -2.7178 0.508)
			(stroke
				(width 0.1524)
				(type default)
			)
			(layer "F.SilkS")
		)
		(fp_line
			(start 2.1336 -1.4224)
			(end -2.7432 -1.4224)
			(stroke
				(width 0.1524)
				(type default)
			)
			(layer "F.SilkS")
		)
		(fp_line
			(start 2.1336 1.4224)
			(end 2.1336 -1.4224)
			(stroke
				(width 0.1524)
				(type default)
			)
			(layer "F.SilkS")
		)
		(fp_poly
			(pts
				(xy -2.2098 -1.4224) (xy -2.2098 1.4224) (xy 2.2098 1.4224) (xy 2.2098 -1.4224)
			)
			(stroke
				(width 0)
				(type default)
			)
			(fill yes)
			(layer "F.SilkS")
		)
		(fp_rect
			(start -2.450084 2.999994)
			(end 2.450084 -2.999994)
			(stroke
				(width 0)
				(type default)
			)
			(fill no)
			(layer "F.CrtYd")
		)
		(fp_poly
			(pts
				(xy -2.8194 3.6322) (xy -2.8194 -3.6322) (xy 2.8194 -3.6322) (xy 2.8194 1.18364) (xy 2.450084 1.18364)
				(xy 2.450084 -2.999994) (xy -2.450084 -2.999994) (xy -2.450084 2.999994) (xy 2.450084 2.999994)
				(xy 2.450084 1.18618) (xy 2.8194 1.18618) (xy 2.8194 3.6322)
			)
			(stroke
				(width 0)
				(type default)
			)
			(fill no)
			(layer "F.CrtYd")
		)
		(fp_rect
			(start -2.8194 3.6322)
			(end 2.8194 -3.6322)
			(stroke
				(width 0)
				(type default)
			)
			(fill no)
			(layer "F.Fab")
		)
		(pad "1" smd rect
			(at -1.905 2.54)
			(size 0.635 1.651)
			(layers "F.Cu" "F.Mask" "F.Paste")
			(net "P12V_B")
		)
		(pad "2" smd rect
			(at -0.635 2.54)
			(size 0.635 1.651)
			(layers "F.Cu" "F.Mask" "F.Paste")
			(net "P12V_B")
		)
		(pad "3" smd rect
			(at 0.635 2.54)
			(size 0.635 1.651)
			(layers "F.Cu" "F.Mask" "F.Paste")
			(net "P12V_B")
		)
		(pad "4" smd rect
			(at 1.905 2.54)
			(size 0.635 1.651)
			(layers "F.Cu" "F.Mask" "F.Paste")
			(net "SW_HDD_N27")
		)
		(pad "5" smd rect
			(at 1.905 -2.54)
			(size 0.635 1.651)
			(layers "F.Cu" "F.Mask" "F.Paste")
			(net "P12V_HDD27")
		)
		(pad "6" smd rect
			(at 0.635 -2.54)
			(size 0.635 1.651)
			(layers "F.Cu" "F.Mask" "F.Paste")
			(net "P12V_HDD27")
		)
		(pad "7" smd rect
			(at -0.635 -2.54)
			(size 0.635 1.651)
			(layers "F.Cu" "F.Mask" "F.Paste")
			(net "P12V_HDD27")
		)
		(pad "8" smd rect
			(at -1.905 -2.54)
			(size 0.635 1.651)
			(layers "F.Cu" "F.Mask" "F.Paste")
			(net "P12V_HDD27")
		)
	)
	(footprint ""
		(layer "F.Cu")
		(at 160.963864 -154.70505)
		(property "Reference" "TP101"
			(at 0 0 0)
			(layer "F.SilkS")
			(hide yes)
			(effects
				(font
					(size 1.27 1.27)
				)
			)
		)
		(property "Value" "*"
			(at -0.0508 -1.6764 0)
			(unlocked yes)
			(layer "F.Fab")
			(hide yes)
			(effects
				(font
					(size 1.016 1.016)
					(thickness 0.1524)
				)
			)
		)
		(property "Device Type" "TPAD32"
			(at -0.0508 -3.2004 0)
			(unlocked yes)
			(layer "F.Fab")
			(hide yes)
			(effects
				(font
					(size 1.016 1.016)
					(thickness 0.1524)
				)
			)
		)
		(duplicate_pad_numbers_are_jumpers no)
		(fp_poly
			(pts
				(arc
					(start 0.4064 0)
					(mid -0.4064 0)
					(end 0.4064 0)
				)
			)
			(stroke
				(width 0)
				(type default)
			)
			(fill no)
			(layer "F.CrtYd")
		)
		(fp_poly
			(pts
				(arc
					(start 0.7112 0)
					(mid -0.7112 0)
					(end 0.7112 0)
				)
			)
			(stroke
				(width 0)
				(type default)
			)
			(fill no)
			(layer "F.Fab")
		)
		(pad "1" smd circle
			(at 0 0)
			(size 0.8128 0.8128)
			(layers "F.Cu" "F.Mask" "F.Paste")
			(net "ACT_HDD_16")
		)
	)
)
